# T6G (Grand Teton) — schematic netlist excerpt (pin names and nets, part order shuffled) for the footprints in the layout excerpt that follows; sources: Cadence DE-HDL packaged netlist, KiCad conversion of 04192023_DAF0TMB3IC0_F0TG_MB_C_brd_V02_OCP.brd

C2492  Q_CAP  22UF 4V 20% X6S  pkg C0402  page 74 : A = PVDD11_S3_P1 ; B = GND
C341  Q_CAP  0.1UF 10V 10% X7S  pkg C0201  page 334 : A = P0V9_CPU1_RT1_2A ; B = GND
C6626  Q_CAP_DIFFBUS  DIFF BUS_0.22UF 6.3V 20% X6S  pkg C0201  page 308 : \1\ = P5E_CPU0_P3_TX_BUF_C_DN<14> ; \2\ = P5E_CPU0_P3_TX_BUF_DN<14>
L5  Q_INDUCTOR  BLM21SN300SN1D/5A IND  pkg SMLF  page 334 : \1\ = P1V8_CPU1_RT_1D ; \2\ = P1V8_CPU1_RT1_1A

(kicad_pcb
	(version 20260206)
	(generator "pcbnew")
	(generator_version "10.0")
	(general
		(thickness 1.6)
		(legacy_teardrops no)
	)
	(paper "A4")
	(title_block
		(title "04192023_DAF0TMB3IC0_F0TG_MB_C_brd_V02_OCP.brd")
		(comment 1 "Grand Teton / footprints 7459-7462 of 8354")
	)
	(layers
		(0 "F.Cu" signal "TOP")
		(4 "In1.Cu" signal "GND")
		(6 "In2.Cu" signal "IN1")
		(8 "In3.Cu" signal "GND1")
		(10 "In4.Cu" signal "IN2")
		(12 "In5.Cu" signal "GND2")
		(14 "In6.Cu" signal "IN3")
		(16 "In7.Cu" signal "GND3")
		(18 "In8.Cu" signal "VCC")
		(20 "In9.Cu" signal "VCC1")
		(22 "In10.Cu" signal "GND4")
		(24 "In11.Cu" signal "IN4")
		(26 "In12.Cu" signal "GND5")
		(28 "In13.Cu" signal "IN5")
		(30 "In14.Cu" signal "GND6")
		(32 "In15.Cu" signal "IN6")
		(34 "In16.Cu" signal "GND7")
		(2 "B.Cu" signal "BOTTOM")
		(9 "F.Adhes" user "F.Adhesive")
		(11 "B.Adhes" user "B.Adhesive")
		(13 "F.Paste" user "Package Geometry/Pastemask Top")
		(15 "B.Paste" user "Package Geometry/Pastemask Bottom")
		(5 "F.SilkS" user "Ref Des/Silkscreen Top")
		(7 "B.SilkS" user "Ref Des/Silkscreen Bottom")
		(1 "F.Mask" user "Board Geometry/Soldermask Top")
		(3 "B.Mask" user "Board Geometry/Soldermask Bottom")
		(17 "Dwgs.User" user "User.Drawings")
		(19 "Cmts.User" user "User.Comments")
		(21 "Eco1.User" user "User.Eco1")
		(23 "Eco2.User" user "User.Eco2")
		(25 "Edge.Cuts" user "Board Geometry/Outline")
		(27 "Margin" user)
		(31 "F.CrtYd" user "Package Geometry/Place Bound Top")
		(29 "B.CrtYd" user "Package Geometry/Place Bound Bottom")
		(35 "F.Fab" user "Ref Des/Assembly Top")
		(33 "B.Fab" user "Ref Des/Assembly Bottom")
	)
	(footprint ""
		(layer "B.Cu")
		(at 415.285682 -416.899344 90)
		(property "Reference" "C6626"
			(at 0 0 90)
			(layer "B.SilkS")
			(hide yes)
			(effects
				(font
					(size 1.27 1.27)
				)
				(justify mirror)
			)
		)
		(property "Value" ""
			(at 0 0 90)
			(layer "B.Fab")
			(effects
				(font
					(size 1.27 1.27)
				)
				(justify mirror)
			)
		)
		(duplicate_pad_numbers_are_jumpers no)
		(fp_line
			(start 0.299974 -0.150114)
			(end -0.299974 -0.150114)
			(stroke
				(width 0.1)
				(type default)
			)
			(layer "B.Fab")
		)
		(fp_line
			(start -0.299974 -0.150114)
			(end -0.299974 0.150114)
			(stroke
				(width 0.1)
				(type default)
			)
			(layer "B.Fab")
		)
		(fp_line
			(start 0.299974 0.150114)
			(end 0.299974 -0.150114)
			(stroke
				(width 0.1)
				(type default)
			)
			(layer "B.Fab")
		)
		(fp_line
			(start -0.299974 0.150114)
			(end 0.299974 0.150114)
			(stroke
				(width 0.1)
				(type default)
			)
			(layer "B.Fab")
		)
		(pad "1" smd rect
			(at 0.2667 0 270)
			(size 0.3048 0.381)
			(layers "B.Cu" "B.Mask" "B.Paste")
			(net "P5E_CPU0_P3_TX_BUF_C_DN<14>")
		)
		(pad "2" smd rect
			(at -0.2667 0 270)
			(size 0.3048 0.381)
			(layers "B.Cu" "B.Mask" "B.Paste")
			(net "P5E_CPU0_P3_TX_BUF_DN<14>")
		)
	)
	(footprint ""
		(layer "B.Cu")
		(at 102.780084 -384.575558)
		(property "Reference" "L5"
			(at 0 0 0)
			(layer "B.SilkS")
			(hide yes)
			(effects
				(font
					(size 1.27 1.27)
				)
				(justify mirror)
			)
		)
		(property "Value" ""
			(at 0 0 0)
			(layer "B.Fab")
			(effects
				(font
					(size 1.27 1.27)
				)
				(justify mirror)
			)
		)
		(duplicate_pad_numbers_are_jumpers no)
		(fp_line
			(start -1.63576 -0.8128)
			(end -1.63576 0.8128)
			(stroke
				(width 0.1524)
				(type default)
			)
			(layer "B.SilkS")
		)
		(fp_line
			(start -1.63576 0.8128)
			(end 1.63576 0.8128)
			(stroke
				(width 0.1524)
				(type default)
			)
			(layer "B.SilkS")
		)
		(fp_line
			(start 1.63576 -0.8128)
			(end -1.63576 -0.8128)
			(stroke
				(width 0.1524)
				(type default)
			)
			(layer "B.SilkS")
		)
		(fp_line
			(start 1.63576 -0.8128)
			(end 1.63576 0.8128)
			(stroke
				(width 0.1524)
				(type default)
			)
			(layer "B.SilkS")
		)
		(fp_line
			(start -1.560576 -0.738632)
			(end 1.56083 -0.738632)
			(stroke
				(width 0.1)
				(type default)
			)
			(layer "B.Fab")
		)
		(fp_line
			(start -1.560576 0.7366)
			(end -1.560576 -0.738632)
			(stroke
				(width 0.1)
				(type default)
			)
			(layer "B.Fab")
		)
		(fp_line
			(start -1.524 0.7366)
			(end -1.560576 0.7366)
			(stroke
				(width 0.1)
				(type default)
			)
			(layer "B.Fab")
		)
		(fp_line
			(start 1.524 0.7366)
			(end -1.524 0.7366)
			(stroke
				(width 0.1)
				(type default)
			)
			(layer "B.Fab")
		)
		(fp_line
			(start 1.56083 -0.738632)
			(end 1.56083 0.7366)
			(stroke
				(width 0.1)
				(type default)
			)
			(layer "B.Fab")
		)
		(fp_line
			(start 1.56083 0.7366)
			(end 1.524 0.7366)
			(stroke
				(width 0.1)
				(type default)
			)
			(layer "B.Fab")
		)
		(pad "1" smd rect
			(at 0.94996 0)
			(size 1.1176 1.3716)
			(layers "B.Cu" "B.Mask" "B.Paste")
			(net "P1V8_CPU1_RT_1D")
		)
		(pad "2" smd rect
			(at -0.94996 0)
			(size 1.1176 1.3716)
			(layers "B.Cu" "B.Mask" "B.Paste")
			(net "P1V8_CPU1_RT1_1A")
		)
	)
	(footprint ""
		(layer "B.Cu")
		(at 80.046322 -388.011162 -90)
		(property "Reference" "C341"
			(at 0 0 90)
			(layer "B.SilkS")
			(hide yes)
			(effects
				(font
					(size 1.27 1.27)
				)
				(justify mirror)
			)
		)
		(property "Value" ""
			(at 0 0 90)
			(layer "B.Fab")
			(effects
				(font
					(size 1.27 1.27)
				)
				(justify mirror)
			)
		)
		(duplicate_pad_numbers_are_jumpers no)
		(fp_line
			(start -0.299974 0.150114)
			(end 0.299974 0.150114)
			(stroke
				(width 0.1)
				(type default)
			)
			(layer "B.Fab")
		)
		(fp_line
			(start 0.299974 0.150114)
			(end 0.299974 -0.150114)
			(stroke
				(width 0.1)
				(type default)
			)
			(layer "B.Fab")
		)
		(fp_line
			(start -0.299974 -0.150114)
			(end -0.299974 0.150114)
			(stroke
				(width 0.1)
				(type default)
			)
			(layer "B.Fab")
		)
		(fp_line
			(start 0.299974 -0.150114)
			(end -0.299974 -0.150114)
			(stroke
				(width 0.1)
				(type default)
			)
			(layer "B.Fab")
		)
		(pad "1" smd rect
			(at 0.2667 0 90)
			(size 0.3048 0.381)
			(layers "B.Cu" "B.Mask" "B.Paste")
			(net "P0V9_CPU1_RT1_2A")
		)
		(pad "2" smd rect
			(at -0.2667 0 90)
			(size 0.3048 0.381)
			(layers "B.Cu" "B.Mask" "B.Paste")
			(net "GND")
		)
	)
	(footprint ""
		(layer "B.Cu")
		(at 117.895624 -262.205216)
		(property "Reference" "C2492"
			(at 0 0 0)
			(layer "B.SilkS")
			(hide yes)
			(effects
				(font
					(size 1.27 1.27)
				)
				(justify mirror)
			)
		)
		(property "Value" ""
			(at 0 0 0)
			(layer "B.Fab")
			(effects
				(font
					(size 1.27 1.27)
				)
				(justify mirror)
			)
		)
		(duplicate_pad_numbers_are_jumpers no)
		(fp_line
			(start -0.7874 -0.4064)
			(end -0.7874 0.4064)
			(stroke
				(width 0.1524)
				(type default)
			)
			(layer "B.SilkS")
		)
		(fp_line
			(start -0.7874 0.4064)
			(end 0.7874 0.4064)
			(stroke
				(width 0.1524)
				(type default)
			)
			(layer "B.SilkS")
		)
		(fp_line
			(start 0.7874 -0.4064)
			(end -0.7874 -0.4064)
			(stroke
				(width 0.1524)
				(type default)
			)
			(layer "B.SilkS")
		)
		(fp_line
			(start 0.7874 0.4064)
			(end 0.7874 -0.4064)
			(stroke
				(width 0.1524)
				(type default)
			)
			(layer "B.SilkS")
		)
		(fp_line
			(start -0.67945 -0.3048)
			(end -0.67945 0.3048)
			(stroke
				(width 0.1)
				(type default)
			)
			(layer "B.Fab")
		)
		(fp_line
			(start -0.67945 0.3048)
			(end -0.120396 0.3048)
			(stroke
				(width 0.1)
				(type default)
			)
			(layer "B.Fab")
		)
		(fp_line
			(start -0.12065 -0.3048)
			(end -0.67945 -0.3048)
			(stroke
				(width 0.1)
				(type default)
			)
			(layer "B.Fab")
		)
		(fp_line
			(start -0.12065 -0.2794)
			(end -0.12065 -0.3048)
			(stroke
				(width 0.1)
				(type default)
			)
			(layer "B.Fab")
		)
		(fp_line
			(start -0.120396 0.2794)
			(end 0.12065 0.2794)
			(stroke
				(width 0.1)
				(type default)
			)
			(layer "B.Fab")
		)
		(fp_line
			(start -0.120396 0.3048)
			(end -0.120396 0.2794)
			(stroke
				(width 0.1)
				(type default)
			)
			(layer "B.Fab")
		)
		(fp_line
			(start 0.12065 -0.305054)
			(end 0.12065 -0.2794)
			(stroke
				(width 0.1)
				(type default)
			)
			(layer "B.Fab")
		)
		(fp_line
			(start 0.12065 -0.2794)
			(end -0.12065 -0.2794)
			(stroke
				(width 0.1)
				(type default)
			)
			(layer "B.Fab")
		)
		(fp_line
			(start 0.12065 0.2794)
			(end 0.12065 0.3048)
			(stroke
				(width 0.1)
				(type default)
			)
			(layer "B.Fab")
		)
		(fp_line
			(start 0.12065 0.3048)
			(end 0.67945 0.3048)
			(stroke
				(width 0.1)
				(type default)
			)
			(layer "B.Fab")
		)
		(fp_line
			(start 0.67945 -0.305054)
			(end 0.12065 -0.305054)
			(stroke
				(width 0.1)
				(type default)
			)
			(layer "B.Fab")
		)
		(fp_line
			(start 0.67945 0.3048)
			(end 0.67945 -0.305054)
			(stroke
				(width 0.1)
				(type default)
			)
			(layer "B.Fab")
		)
		(pad "1" smd circle
			(at 0.40005 0 180)
			(size 0 0)
			(layers "B.Cu" "B.Mask" "B.Paste")
			(net "PVDD11_S3_P1")
		)
		(pad "2" smd circle
			(at -0.40005 0 180)
			(size 0 0)
			(layers "B.Cu" "B.Mask" "B.Paste")
			(net "GND")
		)
	)
)
